# BASEBOARD_FAB2 (Tioga Pass) — schematic netlist excerpt (pin names and nets, part order shuffled) for the footprints in the layout excerpt that follows; sources: Cadence DE-HDL packaged netlist, KiCad conversion of Wiwynn_Tioga_Pass_MB.brd

J6L2  SCONN288_H44441003  SCONN  pkg PIP  page 52
  \12v\(1)  = P12V_NVDIMM_DEF
  VSS(93)  = GND
  DQ(4)  = M_E_DQ<4>
  VSS(92)  = GND
  DQ(0)  = M_E_DQ<0>
  VSS(91)  = GND
  DQS9P  = M_E_DQS_DP<9>
  DQS9N  = M_E_DQS_DN<9>
  VSS(90)  = GND
  DQ(6)  = M_E_DQ<6>
  VSS(89)  = GND
  DQ(2)  = M_E_DQ<2>
  VSS(88)  = GND
  DQ(12)  = M_E_DQ<12>
  VSS(87)  = GND
  DQ(8)  = M_E_DQ<8>
  VSS(86)  = GND
  DQS10P  = M_E_DQS_DP<10>
  DQS10N  = M_E_DQS_DN<10>
  VSS(85)  = GND
  DQ(14)  = M_E_DQ<14>
  VSS(84)  = GND
  DQ(10)  = M_E_DQ<10>
  VSS(83)  = GND
  DQ(20)  = M_E_DQ<20>
  VSS(82)  = GND
  DQ(16)  = M_E_DQ<16>
  VSS(81)  = GND
  DQS11P  = M_E_DQS_DP<11>
  DQS11N  = M_E_DQS_DN<11>
  VSS(80)  = GND
  DQ(22)  = M_E_DQ<22>
  VSS(79)  = GND
  DQ(18)  = M_E_DQ<18>
  VSS(78)  = GND
  DQ(28)  = M_E_DQ<28>
  VSS(77)  = GND
  DQ(24)  = M_E_DQ<24>
  VSS(76)  = GND
  DQS12P  = M_E_DQS_DP<12>
  DQS12N  = M_E_DQS_DN<12>
  VSS(75)  = GND
  DQ(30)  = M_E_DQ<30>
  VSS(74)  = GND
  DQ(26)  = M_E_DQ<26>
  VSS(73)  = GND
  CB(4)  = M_E_ECC<4>
  VSS(72)  = GND
  CB(0)  = M_E_ECC<0>
  VSS(71)  = GND
  DQS17P  = M_E_DQS_DP<17>
  DQS17N  = M_E_DQS_DN<17>
  VSS(70)  = GND
  CB(6)  = M_E_ECC<6>
  VSS(69)  = GND
  CB(2)  = M_E_ECC<2>
  VSS(68)  = GND
  RESET_N  = M_DEF_RST_N
  VDD(25)  = PVDDQ_DEF
  CKE(0)  = M_E_CKE<2>
  VDD(24)  = PVDDQ_DEF
  ACT_N  = M_E_ACT_N
  BG(0)  = M_E_BG<0>
  VDD(23)  = PVDDQ_DEF
  A12  = M_E_MA<12>
  A9  = M_E_MA<9>
  VDD(22)  = PVDDQ_DEF
  A8  = M_E_MA<8>
  A6  = M_E_MA<6>
  VDD(21)  = PVDDQ_DEF
  A3  = M_E_MA<3>
  A1  = M_E_MA<1>
  VDD(20)  = PVDDQ_DEF
  CK0P  = M_E_CLK_DP<2>
  CK0N  = M_E_CLK_DN<2>
  VDD(19)  = PVDDQ_DEF
  VTT(1)  = PVTT_DEF
  EVENT_N  = FM_DIMM_EVENT_COD_N
  A0  = M_E_MA<0>
  VDD(18)  = PVDDQ_DEF
  BA(0)  = M_E_BA<0>
  A16_RAS_N  = M_E_MA<16>
  VDD(17)  = PVDDQ_DEF
  S0_N  = M_E_CS_N<4>
  VDD(16)  = PVDDQ_DEF
  A15_CAS_N  = M_E_MA<15>
  ODT(0)  = M_E_ODT<2>
  VDD(15)  = PVDDQ_DEF
  S1_N  = M_E_CS_N<5>
  VDD(14)  = PVDDQ_DEF
  ODT(1)  = M_E_ODT<3>
  VDD(13)  = PVDDQ_DEF
  S2_N_C(0)  = M_E_CS_N<6>
  VSS(67)  = GND
  DQ(36)  = M_E_DQ<36>
  VSS(66)  = GND
  DQ(32)  = M_E_DQ<32>
  VSS(65)  = GND
  DQS13P  = M_E_DQS_DP<13>
  DQS13N  = M_E_DQS_DN<13>
  VSS(64)  = GND
  DQ(38)  = M_E_DQ<38>
  VSS(63)  = GND
  DQ(34)  = M_E_DQ<34>
  VSS(62)  = GND
  DQ(44)  = M_E_DQ<44>
  VSS(61)  = GND
  DQ(40)  = M_E_DQ<40>
  VSS(60)  = GND
  DQS14P  = M_E_DQS_DP<14>
  DQS14N  = M_E_DQS_DN<14>
  VSS(59)  = GND
  DQ(46)  = M_E_DQ<46>
  VSS(58)  = GND
  DQ(42)  = M_E_DQ<42>
  VSS(57)  = GND
  DQ(52)  = M_E_DQ<52>
  VSS(56)  = GND
  DQ(48)  = M_E_DQ<48>
  VSS(55)  = GND
  DQS15P  = M_E_DQS_DP<15>
  DQS15N  = M_E_DQS_DN<15>
  VSS(54)  = GND
  DQ(54)  = M_E_DQ<54>
  VSS(53)  = GND
  DQ(50)  = M_E_DQ<50>
  VSS(52)  = GND
  DQ(60)  = M_E_DQ<60>
  VSS(51)  = GND
  DQ(56)  = M_E_DQ<56>
  VSS(50)  = GND
  DQS16P  = M_E_DQS_DP<16>
  DQS16N  = M_E_DQS_DN<16>
  VSS(49)  = GND
  DQ(62)  = M_E_DQ<62>
  VSS(48)  = GND
  DQ(58)  = M_E_DQ<58>
  VSS(47)  = GND
  SA(0)  = PVPP_DEF
  SA(1)  = PVPP_DEF
  SCL  = SMB_DDR_DEF_VPP_SCL
  VPP(4)  = PVPP_DEF
  VPP(3)  = PVPP_DEF
  RFU(2)  = TP_CH_E_DIMM_E1_RFU_2
  \12v\(0)  = P12V_NVDIMM_DEF
  VREFCA  = M_E_VREF
  VSS(46)  = GND
  DQ(5)  = M_E_DQ<5>
  VSS(45)  = GND
  DQ(1)  = M_E_DQ<1>
  VSS(44)  = GND
  DQS0N  = M_E_DQS_DN<0>
  DQS0P  = M_E_DQS_DP<0>
  VSS(43)  = GND
  DQ(7)  = M_E_DQ<7>
  VSS(42)  = GND
  DQ(3)  = M_E_DQ<3>
  VSS(41)  = GND
  DQ(13)  = M_E_DQ<13>
  VSS(40)  = GND
  DQ(9)  = M_E_DQ<9>
  VSS(39)  = GND
  DQS1N  = M_E_DQS_DN<1>
  DQS1P  = M_E_DQS_DP<1>
  VSS(38)  = GND
  DQ(15)  = M_E_DQ<15>
  VSS(37)  = GND
  DQ(11)  = M_E_DQ<11>
  VSS(36)  = GND
  DQ(21)  = M_E_DQ<21>
  VSS(35)  = GND
  DQ(17)  = M_E_DQ<17>
  VSS(34)  = GND
  DQS2N  = M_E_DQS_DN<2>
  DQS2P  = M_E_DQS_DP<2>
  VSS(33)  = GND
  DQ(23)  = M_E_DQ<23>
  VSS(32)  = GND
  DQ(19)  = M_E_DQ<19>
  VSS(31)  = GND
  DQ(29)  = M_E_DQ<29>
  VSS(30)  = GND
  DQ(25)  = M_E_DQ<25>
  VSS(29)  = GND
  DQS3N  = M_E_DQS_DN<3>
  DQS3P  = M_E_DQS_DP<3>
  VSS(28)  = GND
  DQ(31)  = M_E_DQ<31>
  VSS(27)  = GND
  DQ(27)  = M_E_DQ<27>
  VSS(26)  = GND
  CB(5)  = M_E_ECC<5>
  VSS(25)  = GND
  CB(1)  = M_E_ECC<1>
  VSS(24)  = GND
  DQS8N  = M_E_DQS_DN<8>
  DQS8P  = M_E_DQS_DP<8>
  VSS(23)  = GND
  CB(7)  = M_E_ECC<7>
  VSS(22)  = GND
  CB(3)  = M_E_ECC<3>
  VSS(21)  = GND
  CKE(1)  = M_E_CKE<3>
  VDD(12)  = PVDDQ_DEF
  RFU(0)  = TP_CH_E_DIMM_E1_RFU_0
  VDD(11)  = PVDDQ_DEF
  BG(1)  = M_E_BG<1>
  ALERT_N  = M_E_ALERT_N
  VDD(10)  = PVDDQ_DEF
  A11  = M_E_MA<11>
  A7  = M_E_MA<7>
  VDD(9)  = PVDDQ_DEF
  A5  = M_E_MA<5>
  A4  = M_E_MA<4>
  VDD(8)  = PVDDQ_DEF
  A2  = M_E_MA<2>
  VDD(7)  = PVDDQ_DEF
  CK1P  = M_E_CLK_DP<3>
  CK1N  = M_E_CLK_DN<3>
  VDD(6)  = PVDDQ_DEF
  VTT(0)  = PVTT_DEF
  PAR  = M_E_PAR
  VDD(5)  = PVDDQ_DEF
  BA(1)  = M_E_BA<1>
  A10  = M_E_MA<10>
  VDD(4)  = PVDDQ_DEF
  RFU(1)  = TP_CH_E_DIMM_E1_RFU_1
  A14_WE_N  = M_E_MA<14>
  VDD(3)  = PVDDQ_DEF
  SAVE_N_NC  = FM_ADR_COMPLETE_DEF_N
  VDD(2)  = PVDDQ_DEF
  A13  = M_E_MA<13>
  VDD(1)  = PVDDQ_DEF
  A17  = M_E_MA<17>
  C(2)  = M_E_C<2>
  VDD(0)  = PVDDQ_DEF
  S3_N_C(1)  = M_E_CS_N<7>
  SA(2)  = GND
  VSS(20)  = GND
  DQ(37)  = M_E_DQ<37>
  VSS(19)  = GND
  DQ(33)  = M_E_DQ<33>
  VSS(18)  = GND
  DQS4N  = M_E_DQS_DN<4>
  DQS4P  = M_E_DQS_DP<4>
  VSS(17)  = GND
  DQ(39)  = M_E_DQ<39>
  VSS(16)  = GND
  DQ(35)  = M_E_DQ<35>
  VSS(15)  = GND
  DQ(45)  = M_E_DQ<45>
  VSS(14)  = GND
  DQ(41)  = M_E_DQ<41>
  VSS(13)  = GND
  DQS5N  = M_E_DQS_DN<5>
  DQS5P  = M_E_DQS_DP<5>
  VSS(12)  = GND
  DQ(47)  = M_E_DQ<47>
  VSS(11)  = GND
  DQ(43)  = M_E_DQ<43>
  VSS(10)  = GND
  DQ(53)  = M_E_DQ<53>
  VSS(9)  = GND
  DQ(49)  = M_E_DQ<49>
  VSS(8)  = GND
  DQS6N  = M_E_DQS_DN<6>
  DQS6P  = M_E_DQS_DP<6>
  VSS(7)  = GND
  DQ(55)  = M_E_DQ<55>
  VSS(6)  = GND
  DQ(51)  = M_E_DQ<51>
  VSS(5)  = GND
  DQ(61)  = M_E_DQ<61>
  VSS(4)  = GND
  DQ(57)  = M_E_DQ<57>
  VSS(3)  = GND
  DQS7N  = M_E_DQS_DN<7>
  DQS7P  = M_E_DQS_DP<7>
  VSS(2)  = GND
  DQ(63)  = M_E_DQ<63>
  VSS(1)  = GND
  DQ(59)  = M_E_DQ<59>
  VSS(0)  = GND
  VDDSPD  = PVPP_DEF
  SDA  = SMB_DDR_DEF_VPP_SDA
  VPP(1)  = PVPP_DEF
  VPP(0)  = PVPP_DEF
  VPP(2)  = PVPP_DEF

(kicad_pcb
	(version 20260206)
	(generator "pcbnew")
	(generator_version "10.0")
	(general
		(thickness 1.6)
		(legacy_teardrops no)
	)
	(paper "A4")
	(title_block
		(title "Wiwynn_Tioga_Pass_MB.brd")
		(comment 1 "Tioga Pass / footprint 3319 of 4770 (J6L2), pads 101-151 of 291")
	)
	(layers
		(0 "F.Cu" signal "TOP")
		(4 "In1.Cu" signal "L2GND")
		(6 "In2.Cu" signal "L3")
		(8 "In3.Cu" signal "L4GND")
		(10 "In4.Cu" signal "L5")
		(12 "In5.Cu" signal "L6GND")
		(14 "In6.Cu" signal "L7VCC")
		(16 "In7.Cu" signal "L8VCC")
		(18 "In8.Cu" signal "L9GND")
		(20 "In9.Cu" signal "L10")
		(22 "In10.Cu" signal "L11GND")
		(24 "In11.Cu" signal "L12")
		(26 "In12.Cu" signal "L13GND")
		(2 "B.Cu" signal "BOTTOM")
		(9 "F.Adhes" user "F.Adhesive")
		(11 "B.Adhes" user "B.Adhesive")
		(13 "F.Paste" user "Package Geometry/Pastemask Top")
		(15 "B.Paste" user "Package Geometry/Pastemask Bottom")
		(5 "F.SilkS" user "Ref Des/Silkscreen Top")
		(7 "B.SilkS" user "Ref Des/Silkscreen Bottom")
		(1 "F.Mask" user "Board Geometry/Soldermask Top")
		(3 "B.Mask" user "Board Geometry/Soldermask Bottom")
		(17 "Dwgs.User" user "User.Drawings")
		(19 "Cmts.User" user "User.Comments")
		(21 "Eco1.User" user "User.Eco1")
		(23 "Eco2.User" user "User.Eco2")
		(25 "Edge.Cuts" user "Board Geometry/Outline")
		(27 "Margin" user)
		(31 "F.CrtYd" user "Package Geometry/Place Bound Top")
		(29 "B.CrtYd" user "Package Geometry/Place Bound Bottom")
		(35 "F.Fab" user "Ref Des/Assembly Top")
		(33 "B.Fab" user "Ref Des/Assembly Bottom")
	)
	(footprint ""
		(layer "B.Cu")
		(at 194.700398 -142.477236 90)
		(property "Reference" "J6L2"
			(at 2.276348 38.21811 0)
			(unlocked yes)
			(layer "B.SilkS")
			(effects
				(font
					(size 0.7874 0.5842)
					(thickness 0.1524)
				)
				(justify left mirror)
			)
		)
		(property "Value" ""
			(at 0 0 90)
			(layer "B.Fab")
			(effects
				(font
					(size 1.27 1.27)
				)
				(justify mirror)
			)
		)
		(duplicate_pad_numbers_are_jumpers no)
		(pad "98" smd rect
			(at 0 87.54999 270)
			(size 1.8034 0.508)
			(layers "B.Cu" "B.Mask" "B.Paste")
			(net "GND")
		)
		(pad "99" smd rect
			(at 0 88.399874 270)
			(size 1.8034 0.508)
			(layers "B.Cu" "B.Mask" "B.Paste")
			(net "M_E_DQS_DP<13>")
		)
		(pad "100" smd rect
			(at 0 89.250012 270)
			(size 1.8034 0.508)
			(layers "B.Cu" "B.Mask" "B.Paste")
			(net "M_E_DQS_DN<13>")
		)
		(pad "101" smd rect
			(at 0 90.099896 270)
			(size 1.8034 0.508)
			(layers "B.Cu" "B.Mask" "B.Paste")
			(net "GND")
		)
		(pad "102" smd rect
			(at 0 90.950034 270)
			(size 1.8034 0.508)
			(layers "B.Cu" "B.Mask" "B.Paste")
			(net "M_E_DQ<38>")
		)
		(pad "103" smd rect
			(at 0 91.799918 270)
			(size 1.8034 0.508)
			(layers "B.Cu" "B.Mask" "B.Paste")
			(net "GND")
		)
		(pad "104" smd rect
			(at 0 92.650056 270)
			(size 1.8034 0.508)
			(layers "B.Cu" "B.Mask" "B.Paste")
			(net "M_E_DQ<34>")
		)
		(pad "105" smd rect
			(at 0 93.49994 270)
			(size 1.8034 0.508)
			(layers "B.Cu" "B.Mask" "B.Paste")
			(net "GND")
		)
		(pad "106" smd rect
			(at 0 94.350078 270)
			(size 1.8034 0.508)
			(layers "B.Cu" "B.Mask" "B.Paste")
			(net "M_E_DQ<44>")
		)
		(pad "107" smd rect
			(at 0 95.199962 270)
			(size 1.8034 0.508)
			(layers "B.Cu" "B.Mask" "B.Paste")
			(net "GND")
		)
		(pad "108" smd rect
			(at 0 96.0501 270)
			(size 1.8034 0.508)
			(layers "B.Cu" "B.Mask" "B.Paste")
			(net "M_E_DQ<40>")
		)
		(pad "109" smd rect
			(at 0 96.899984 270)
			(size 1.8034 0.508)
			(layers "B.Cu" "B.Mask" "B.Paste")
			(net "GND")
		)
		(pad "110" smd rect
			(at 0 97.750122 270)
			(size 1.8034 0.508)
			(layers "B.Cu" "B.Mask" "B.Paste")
			(net "M_E_DQS_DP<14>")
		)
		(pad "111" smd rect
			(at 0 98.600006 270)
			(size 1.8034 0.508)
			(layers "B.Cu" "B.Mask" "B.Paste")
			(net "M_E_DQS_DN<14>")
		)
		(pad "112" smd rect
			(at 0 99.44989 270)
			(size 1.8034 0.508)
			(layers "B.Cu" "B.Mask" "B.Paste")
			(net "GND")
		)
		(pad "113" smd rect
			(at 0 100.300028 270)
			(size 1.8034 0.508)
			(layers "B.Cu" "B.Mask" "B.Paste")
			(net "M_E_DQ<46>")
		)
		(pad "114" smd rect
			(at 0 101.149912 270)
			(size 1.8034 0.508)
			(layers "B.Cu" "B.Mask" "B.Paste")
			(net "GND")
		)
		(pad "115" smd rect
			(at 0 102.00005 270)
			(size 1.8034 0.508)
			(layers "B.Cu" "B.Mask" "B.Paste")
			(net "M_E_DQ<42>")
		)
		(pad "116" smd rect
			(at 0 102.849934 270)
			(size 1.8034 0.508)
			(layers "B.Cu" "B.Mask" "B.Paste")
			(net "GND")
		)
		(pad "117" smd rect
			(at 0 103.700072 270)
			(size 1.8034 0.508)
			(layers "B.Cu" "B.Mask" "B.Paste")
			(net "M_E_DQ<52>")
		)
		(pad "118" smd rect
			(at 0 104.549956 270)
			(size 1.8034 0.508)
			(layers "B.Cu" "B.Mask" "B.Paste")
			(net "GND")
		)
		(pad "119" smd rect
			(at 0 105.400094 270)
			(size 1.8034 0.508)
			(layers "B.Cu" "B.Mask" "B.Paste")
			(net "M_E_DQ<48>")
		)
		(pad "120" smd rect
			(at 0 106.249978 270)
			(size 1.8034 0.508)
			(layers "B.Cu" "B.Mask" "B.Paste")
			(net "GND")
		)
		(pad "121" smd rect
			(at 0 107.100116 270)
			(size 1.8034 0.508)
			(layers "B.Cu" "B.Mask" "B.Paste")
			(net "M_E_DQS_DP<15>")
		)
		(pad "122" smd rect
			(at 0 107.95 270)
			(size 1.8034 0.508)
			(layers "B.Cu" "B.Mask" "B.Paste")
			(net "M_E_DQS_DN<15>")
		)
		(pad "123" smd rect
			(at 0 108.799884 270)
			(size 1.8034 0.508)
			(layers "B.Cu" "B.Mask" "B.Paste")
			(net "GND")
		)
		(pad "124" smd rect
			(at 0 109.650022 270)
			(size 1.8034 0.508)
			(layers "B.Cu" "B.Mask" "B.Paste")
			(net "M_E_DQ<54>")
		)
		(pad "125" smd rect
			(at 0 110.499906 270)
			(size 1.8034 0.508)
			(layers "B.Cu" "B.Mask" "B.Paste")
			(net "GND")
		)
		(pad "126" smd rect
			(at 0 111.350044 270)
			(size 1.8034 0.508)
			(layers "B.Cu" "B.Mask" "B.Paste")
			(net "M_E_DQ<50>")
		)
		(pad "127" smd rect
			(at 0 112.199928 270)
			(size 1.8034 0.508)
			(layers "B.Cu" "B.Mask" "B.Paste")
			(net "GND")
		)
		(pad "128" smd rect
			(at 0 113.050066 270)
			(size 1.8034 0.508)
			(layers "B.Cu" "B.Mask" "B.Paste")
			(net "M_E_DQ<60>")
		)
		(pad "129" smd rect
			(at 0 113.89995 270)
			(size 1.8034 0.508)
			(layers "B.Cu" "B.Mask" "B.Paste")
			(net "GND")
		)
		(pad "130" smd rect
			(at 0 114.750088 270)
			(size 1.8034 0.508)
			(layers "B.Cu" "B.Mask" "B.Paste")
			(net "M_E_DQ<56>")
		)
		(pad "131" smd rect
			(at 0 115.599972 270)
			(size 1.8034 0.508)
			(layers "B.Cu" "B.Mask" "B.Paste")
			(net "GND")
		)
		(pad "132" smd rect
			(at 0 116.45011 270)
			(size 1.8034 0.508)
			(layers "B.Cu" "B.Mask" "B.Paste")
			(net "M_E_DQS_DP<16>")
		)
		(pad "133" smd rect
			(at 0 117.299994 270)
			(size 1.8034 0.508)
			(layers "B.Cu" "B.Mask" "B.Paste")
			(net "M_E_DQS_DN<16>")
		)
		(pad "134" smd rect
			(at 0 118.149878 270)
			(size 1.8034 0.508)
			(layers "B.Cu" "B.Mask" "B.Paste")
			(net "GND")
		)
		(pad "135" smd rect
			(at 0 119.000016 270)
			(size 1.8034 0.508)
			(layers "B.Cu" "B.Mask" "B.Paste")
			(net "M_E_DQ<62>")
		)
		(pad "136" smd rect
			(at 0 119.8499 270)
			(size 1.8034 0.508)
			(layers "B.Cu" "B.Mask" "B.Paste")
			(net "GND")
		)
		(pad "137" smd rect
			(at 0 120.700038 270)
			(size 1.8034 0.508)
			(layers "B.Cu" "B.Mask" "B.Paste")
			(net "M_E_DQ<58>")
		)
		(pad "138" smd rect
			(at 0 121.549922 270)
			(size 1.8034 0.508)
			(layers "B.Cu" "B.Mask" "B.Paste")
			(net "GND")
		)
		(pad "139" smd rect
			(at 0 122.40006 270)
			(size 1.8034 0.508)
			(layers "B.Cu" "B.Mask" "B.Paste")
			(net "PVPP_DEF")
		)
		(pad "140" smd rect
			(at 0 123.249944 270)
			(size 1.8034 0.508)
			(layers "B.Cu" "B.Mask" "B.Paste")
			(net "PVPP_DEF")
		)
		(pad "141" smd rect
			(at 0 124.100082 270)
			(size 1.8034 0.508)
			(layers "B.Cu" "B.Mask" "B.Paste")
			(net "SMB_DDR_DEF_VPP_SCL")
		)
		(pad "142" smd rect
			(at 0 124.949966 270)
			(size 1.8034 0.508)
			(layers "B.Cu" "B.Mask" "B.Paste")
			(net "PVPP_DEF")
		)
		(pad "143" smd rect
			(at 0 125.800104 270)
			(size 1.8034 0.508)
			(layers "B.Cu" "B.Mask" "B.Paste")
			(net "PVPP_DEF")
		)
		(pad "144" smd rect
			(at 0 126.649988 270)
			(size 1.8034 0.508)
			(layers "B.Cu" "B.Mask" "B.Paste")
			(net "TP_CH_E_DIMM_E1_RFU_2")
		)
		(pad "145" smd rect
			(at -4.59994 0 270)
			(size 1.8034 0.508)
			(layers "B.Cu" "B.Mask" "B.Paste")
			(net "P12V_NVDIMM_DEF")
		)
		(pad "146" smd rect
			(at -4.59994 0.849884 270)
			(size 1.8034 0.508)
			(layers "B.Cu" "B.Mask" "B.Paste")
			(net "M_E_VREF")
		)
		(pad "147" smd rect
			(at -4.59994 1.700022 270)
			(size 1.8034 0.508)
			(layers "B.Cu" "B.Mask" "B.Paste")
			(net "GND")
		)
		(pad "148" smd rect
			(at -4.59994 2.549906 270)
			(size 1.8034 0.508)
			(layers "B.Cu" "B.Mask" "B.Paste")
			(net "M_E_DQ<5>")
		)
	)
)
